# BASEBOARD_FAB2 (Tioga Pass) — schematic netlist excerpt (pin names and nets, part order shuffled) for the footprints in the layout excerpt that follows; sources: Cadence DE-HDL packaged netlist, KiCad conversion of Wiwynn_Tioga_Pass_MB.brd

C2G3  CAP_A  47UF 4V 20% X5R  pkg 0603V  page 225 : A = PVDDQ_GHJ ; B = GND
CR10W2  DIODE  SDMK0340L EMPTY  pkg SM  page 251 : C = P5V_STBY ; A = PUMP_PWM_OUT_R
R8A6  RES  1.00K 1% CHIP  pkg 0402  page 235 : A = P3V3_STBY ; B = PWRGD_PVNN_PCH_R

(kicad_pcb
	(version 20260206)
	(generator "pcbnew")
	(generator_version "10.0")
	(general
		(thickness 1.6)
		(legacy_teardrops no)
	)
	(paper "A4")
	(title_block
		(title "Wiwynn_Tioga_Pass_MB.brd")
		(comment 1 "Tioga Pass / footprints 2045-2047 of 4770")
	)
	(layers
		(0 "F.Cu" signal "TOP")
		(4 "In1.Cu" signal "L2GND")
		(6 "In2.Cu" signal "L3")
		(8 "In3.Cu" signal "L4GND")
		(10 "In4.Cu" signal "L5")
		(12 "In5.Cu" signal "L6GND")
		(14 "In6.Cu" signal "L7VCC")
		(16 "In7.Cu" signal "L8VCC")
		(18 "In8.Cu" signal "L9GND")
		(20 "In9.Cu" signal "L10")
		(22 "In10.Cu" signal "L11GND")
		(24 "In11.Cu" signal "L12")
		(26 "In12.Cu" signal "L13GND")
		(2 "B.Cu" signal "BOTTOM")
		(9 "F.Adhes" user "F.Adhesive")
		(11 "B.Adhes" user "B.Adhesive")
		(13 "F.Paste" user "Package Geometry/Pastemask Top")
		(15 "B.Paste" user "Package Geometry/Pastemask Bottom")
		(5 "F.SilkS" user "Ref Des/Silkscreen Top")
		(7 "B.SilkS" user "Ref Des/Silkscreen Bottom")
		(1 "F.Mask" user "Board Geometry/Soldermask Top")
		(3 "B.Mask" user "Board Geometry/Soldermask Bottom")
		(17 "Dwgs.User" user "User.Drawings")
		(19 "Cmts.User" user "User.Comments")
		(21 "Eco1.User" user "User.Eco1")
		(23 "Eco2.User" user "User.Eco2")
		(25 "Edge.Cuts" user "Board Geometry/Outline")
		(27 "Margin" user)
		(31 "F.CrtYd" user "Package Geometry/Place Bound Top")
		(29 "B.CrtYd" user "Package Geometry/Place Bound Bottom")
		(35 "F.Fab" user "Ref Des/Assembly Top")
		(33 "B.Fab" user "Ref Des/Assembly Bottom")
	)
	(footprint ""
		(layer "F.Cu")
		(at 87.158068 -12.954 -90)
		(property "Reference" "C2G3"
			(at 1.848866 0.752348 270)
			(unlocked yes)
			(layer "F.SilkS")
			(effects
				(font
					(size 1.27 0.9652)
					(thickness 0.1524)
				)
			)
		)
		(property "Value" ""
			(at 0 0 270)
			(layer "F.Fab")
			(effects
				(font
					(size 1.27 1.27)
				)
			)
		)
		(duplicate_pad_numbers_are_jumpers no)
		(fp_rect
			(start -0.500126 1.598422)
			(end 0.500126 -0.201422)
			(stroke
				(width 0)
				(type default)
			)
			(fill no)
			(layer "F.CrtYd")
		)
		(fp_line
			(start -0.500126 1.598422)
			(end -0.500126 -0.201422)
			(stroke
				(width 0.1)
				(type default)
			)
			(layer "F.Fab")
		)
		(fp_line
			(start 0.500126 1.598422)
			(end -0.500126 1.598422)
			(stroke
				(width 0.1)
				(type default)
			)
			(layer "F.Fab")
		)
		(fp_line
			(start -0.500126 -0.201422)
			(end 0.500126 -0.201422)
			(stroke
				(width 0.1)
				(type default)
			)
			(layer "F.Fab")
		)
		(fp_line
			(start 0.500126 -0.201422)
			(end 0.500126 1.598422)
			(stroke
				(width 0.1)
				(type default)
			)
			(layer "F.Fab")
		)
		(pad "1" smd rect
			(at 0 0 180)
			(size 0.889 0.9906)
			(layers "F.Cu" "F.Mask" "F.Paste")
			(net "PVDDQ_GHJ")
		)
		(pad "2" smd rect
			(at 0 1.397 180)
			(size 0.889 0.9906)
			(layers "F.Cu" "F.Mask" "F.Paste")
			(net "GND")
		)
		(zone
			(layer "F.Cu")
			(hatch none 0.5)
			(connect_pads
				(clearance 0)
			)
			(min_thickness 0.25)
			(keepout
				(tracks not_allowed)
				(vias allowed)
				(pads allowed)
				(copperpour not_allowed)
				(footprints allowed)
			)
			(placement
				(enabled no)
				(sheetname "")
			)
			(fill
				(thermal_gap 0.5)
				(thermal_bridge_width 0.5)
				(island_removal_mode 0)
			)
			(polygon
				(pts
					(xy 86.205568 -13.4493) (xy 86.205568 -12.4587) (xy 86.713568 -12.4587) (xy 86.713568 -13.4493)
				)
			)
		)
		(zone
			(layer "F.Cu")
			(hatch none 0.5)
			(connect_pads
				(clearance 0)
			)
			(min_thickness 0.25)
			(keepout
				(tracks allowed)
				(vias not_allowed)
				(pads allowed)
				(copperpour not_allowed)
				(footprints allowed)
			)
			(placement
				(enabled no)
				(sheetname "")
			)
			(fill
				(thermal_gap 0.5)
				(thermal_bridge_width 0.5)
				(island_removal_mode 0)
			)
			(polygon
				(pts
					(xy 86.205568 -13.4493) (xy 86.205568 -12.4587) (xy 86.713568 -12.4587) (xy 86.713568 -13.4493)
				)
			)
		)
	)
	(footprint ""
		(layer "F.Cu")
		(at 427.609 -20.955 90)
		(property "Reference" "CR10W2"
			(at 1.06934 -0.39116 0)
			(unlocked yes)
			(layer "F.SilkS")
			(effects
				(font
					(size 0.4064 0.254)
					(thickness 0.1524)
				)
				(justify left)
			)
		)
		(property "Value" ""
			(at 0 0 90)
			(layer "F.Fab")
			(effects
				(font
					(size 1.27 1.27)
				)
			)
		)
		(duplicate_pad_numbers_are_jumpers no)
		(fp_line
			(start 1.103122 1.054354)
			(end 1.103122 2.177796)
			(stroke
				(width 0.1524)
				(type default)
			)
			(layer "F.SilkS")
		)
		(fp_line
			(start 1.583944 2.177796)
			(end 0.6223 2.177796)
			(stroke
				(width 0.1524)
				(type default)
			)
			(layer "F.SilkS")
		)
		(fp_line
			(start 1.103122 2.177796)
			(end 1.583944 3.010662)
			(stroke
				(width 0.1524)
				(type default)
			)
			(layer "F.SilkS")
		)
		(fp_line
			(start 1.583944 3.010662)
			(end 1.103122 3.010662)
			(stroke
				(width 0.1524)
				(type default)
			)
			(layer "F.SilkS")
		)
		(fp_line
			(start 1.103122 3.010662)
			(end 0.6223 3.010662)
			(stroke
				(width 0.1524)
				(type default)
			)
			(layer "F.SilkS")
		)
		(fp_line
			(start 0.6223 3.010662)
			(end 1.103122 2.177796)
			(stroke
				(width 0.1524)
				(type default)
			)
			(layer "F.SilkS")
		)
		(fp_line
			(start 1.103122 3.922268)
			(end 1.103122 3.010662)
			(stroke
				(width 0.1524)
				(type default)
			)
			(layer "F.SilkS")
		)
		(fp_poly
			(pts
				(xy -0.67437 0.24384) (xy -0.67437 2.04216) (xy 0.67437 2.04216) (xy 0.67437 0.24384)
			)
			(stroke
				(width 0)
				(type default)
			)
			(fill no)
			(layer "F.CrtYd")
		)
		(fp_line
			(start 0.67437 0.24384)
			(end -0.67437 0.24384)
			(stroke
				(width 0.1)
				(type default)
			)
			(layer "F.Fab")
		)
		(fp_line
			(start -0.67437 0.24384)
			(end -0.67437 2.04216)
			(stroke
				(width 0.1)
				(type default)
			)
			(layer "F.Fab")
		)
		(fp_line
			(start 0.67437 2.04216)
			(end 0.67437 0.24384)
			(stroke
				(width 0.1)
				(type default)
			)
			(layer "F.Fab")
		)
		(fp_line
			(start -0.67437 2.04216)
			(end 0.67437 2.04216)
			(stroke
				(width 0.1)
				(type default)
			)
			(layer "F.Fab")
		)
		(fp_line
			(start 1.583944 2.177796)
			(end 0.6223 2.177796)
			(stroke
				(width 0.1)
				(type default)
			)
			(layer "F.Fab")
		)
		(fp_line
			(start 1.103122 2.177796)
			(end 1.103122 1.054354)
			(stroke
				(width 0.1)
				(type default)
			)
			(layer "F.Fab")
		)
		(fp_line
			(start 1.103122 2.177796)
			(end 1.583944 3.010662)
			(stroke
				(width 0.1)
				(type default)
			)
			(layer "F.Fab")
		)
		(fp_line
			(start 1.583944 3.010662)
			(end 0.6223 3.010662)
			(stroke
				(width 0.1)
				(type default)
			)
			(layer "F.Fab")
		)
		(fp_line
			(start 1.103122 3.010662)
			(end 1.103122 3.922268)
			(stroke
				(width 0.1)
				(type default)
			)
			(layer "F.Fab")
		)
		(fp_line
			(start 0.6223 3.010662)
			(end 1.103122 2.177796)
			(stroke
				(width 0.1)
				(type default)
			)
			(layer "F.Fab")
		)
		(pad "1" smd rect
			(at 0 0 90)
			(size 0.4064 1.016)
			(layers "F.Cu" "F.Mask" "F.Paste")
			(net "P5V_STBY")
		)
		(pad "2" smd rect
			(at 0 2.286 90)
			(size 0.4064 1.016)
			(layers "F.Cu" "F.Mask" "F.Paste")
			(net "PUMP_PWM_OUT_R")
		)
	)
	(footprint ""
		(layer "F.Cu")
		(at 399.159222 -149.225 180)
		(property "Reference" "R8A6"
			(at 0 0 180)
			(layer "F.SilkS")
			(hide yes)
			(effects
				(font
					(size 1.27 1.27)
				)
			)
		)
		(property "Value" ""
			(at 0 0 180)
			(layer "F.Fab")
			(effects
				(font
					(size 1.27 1.27)
				)
			)
		)
		(duplicate_pad_numbers_are_jumpers no)
		(fp_poly
			(pts
				(xy -0.2794 -0.1016) (xy 0.2794 -0.1016) (xy 0.2794 0.9906) (xy -0.2794 0.9906)
			)
			(stroke
				(width 0)
				(type default)
			)
			(fill no)
			(layer "F.CrtYd")
		)
		(fp_line
			(start 0.2794 0.9906)
			(end 0.2794 -0.1016)
			(stroke
				(width 0.1)
				(type default)
			)
			(layer "F.Fab")
		)
		(fp_line
			(start 0.2794 -0.1016)
			(end -0.2794 -0.1016)
			(stroke
				(width 0.1)
				(type default)
			)
			(layer "F.Fab")
		)
		(fp_line
			(start -0.2794 0.9906)
			(end 0.2794 0.9906)
			(stroke
				(width 0.1)
				(type default)
			)
			(layer "F.Fab")
		)
		(fp_line
			(start -0.2794 -0.1016)
			(end -0.2794 0.9906)
			(stroke
				(width 0.1)
				(type default)
			)
			(layer "F.Fab")
		)
		(pad "1" smd rect
			(at 0 0 180)
			(size 0.508 0.508)
			(layers "F.Cu" "F.Mask" "F.Paste")
			(net "P3V3_STBY")
		)
		(pad "2" smd rect
			(at 0 0.889 180)
			(size 0.508 0.508)
			(layers "F.Cu" "F.Mask" "F.Paste")
			(net "PWRGD_PVNN_PCH_R")
		)
		(zone
			(layer "F.Cu")
			(hatch none 0.5)
			(connect_pads
				(clearance 0)
			)
			(min_thickness 0.25)
			(keepout
				(tracks not_allowed)
				(vias allowed)
				(pads allowed)
				(copperpour not_allowed)
				(footprints allowed)
			)
			(placement
				(enabled no)
				(sheetname "")
			)
			(fill
				(thermal_gap 0.5)
				(thermal_bridge_width 0.5)
				(island_removal_mode 0)
			)
			(polygon
				(pts
					(xy 399.413222 -149.86) (xy 398.905222 -149.86) (xy 398.905222 -149.479) (xy 399.413222 -149.479)
				)
			)
		)
		(zone
			(layer "F.Cu")
			(hatch none 0.5)
			(connect_pads
				(clearance 0)
			)
			(min_thickness 0.25)
			(keepout
				(tracks allowed)
				(vias not_allowed)
				(pads allowed)
				(copperpour not_allowed)
				(footprints allowed)
			)
			(placement
				(enabled no)
				(sheetname "")
			)
			(fill
				(thermal_gap 0.5)
				(thermal_bridge_width 0.5)
				(island_removal_mode 0)
			)
			(polygon
				(pts
					(xy 399.413222 -149.479) (xy 398.905222 -149.479) (xy 398.905222 -149.86) (xy 399.413222 -149.86)
				)
			)
		)
	)
)
